(kicad_pcb
	(version 20260206)
	(generator "pcbnew")
	(generator_version "10.0")
	(general
		(thickness 1.6)
		(legacy_teardrops no)
	)
	(paper "A4")
	(title_block
		(title "Bryce Canyon_R.DPB_16317-1_OCP.brd")
		(comment 1 "Bryce Canyon / footprints 307-313 of 2099")
	)
	(layers
		(0 "F.Cu" signal "TOP")
		(4 "In1.Cu" signal "L2GND")
		(6 "In2.Cu" signal "L3")
		(8 "In3.Cu" signal "L4VCC")
		(10 "In4.Cu" signal "L5VCC")
		(12 "In5.Cu" signal "L6")
		(14 "In6.Cu" signal "L7GND")
		(2 "B.Cu" signal "BOTTOM")
		(9 "F.Adhes" user "F.Adhesive")
		(11 "B.Adhes" user "B.Adhesive")
		(13 "F.Paste" user "Package Geometry/Pastemask Top")
		(15 "B.Paste" user "Package Geometry/Pastemask Bottom")
		(5 "F.SilkS" user "Ref Des/Silkscreen Top")
		(7 "B.SilkS" user "Ref Des/Silkscreen Bottom")
		(1 "F.Mask" user "Board Geometry/Soldermask Top")
		(3 "B.Mask" user "Board Geometry/Soldermask Bottom")
		(17 "Dwgs.User" user "User.Drawings")
		(19 "Cmts.User" user "User.Comments")
		(21 "Eco1.User" user "User.Eco1")
		(23 "Eco2.User" user "User.Eco2")
		(25 "Edge.Cuts" user "Board Geometry/Outline")
		(27 "Margin" user)
		(31 "F.CrtYd" user "Package Geometry/Place Bound Top")
		(29 "B.CrtYd" user "Package Geometry/Place Bound Bottom")
		(35 "F.Fab" user "Ref Des/Assembly Top")
		(33 "B.Fab" user "Ref Des/Assembly Bottom")
	)
	(footprint ""
		(layer "F.Cu")
		(at 475.742 -26.162 180)
		(property "Reference" "Q183"
			(at 0 0 180)
			(layer "F.SilkS")
			(hide yes)
			(effects
				(font
					(size 1.27 1.27)
				)
			)
		)
		(property "Value" "AO4406AL-GP"
			(at -3.707384 -1.5367 180)
			(unlocked yes)
			(layer "F.Fab")
			(hide yes)
			(effects
				(font
					(size 1.016 1.016)
					(thickness 0.1524)
				)
			)
		)
		(property "Device Type" "SOIC8H69"
			(at -3.707384 -3.0607 180)
			(unlocked yes)
			(layer "F.Fab")
			(hide yes)
			(effects
				(font
					(size 1.016 1.016)
					(thickness 0.1524)
				)
			)
		)
		(duplicate_pad_numbers_are_jumpers no)
		(fp_line
			(start 2.1336 1.4224)
			(end 2.1336 -1.4224)
			(stroke
				(width 0.1524)
				(type default)
			)
			(layer "F.SilkS")
		)
		(fp_line
			(start 2.1336 -1.4224)
			(end -2.7432 -1.4224)
			(stroke
				(width 0.1524)
				(type default)
			)
			(layer "F.SilkS")
		)
		(fp_line
			(start -2.1844 -0.0508)
			(end -2.7178 0.508)
			(stroke
				(width 0.1524)
				(type default)
			)
			(layer "F.SilkS")
		)
		(fp_line
			(start -2.6289 3.4417)
			(end -2.6289 1.4732)
			(stroke
				(width 0.381)
				(type default)
			)
			(layer "F.SilkS")
		)
		(fp_line
			(start -2.7178 -0.508)
			(end -2.1844 -0.0508)
			(stroke
				(width 0.1524)
				(type default)
			)
			(layer "F.SilkS")
		)
		(fp_line
			(start -2.7432 1.4224)
			(end 2.1336 1.4224)
			(stroke
				(width 0.1524)
				(type default)
			)
			(layer "F.SilkS")
		)
		(fp_line
			(start -2.7432 1.4224)
			(end -2.6416 1.4224)
			(stroke
				(width 0.1524)
				(type default)
			)
			(layer "F.SilkS")
		)
		(fp_line
			(start -2.7432 -1.4224)
			(end -2.7432 1.4224)
			(stroke
				(width 0.1524)
				(type default)
			)
			(layer "F.SilkS")
		)
		(fp_poly
			(pts
				(xy -2.2098 -1.4224) (xy -2.2098 1.4224) (xy 2.2098 1.4224) (xy 2.2098 -1.4224)
			)
			(stroke
				(width 0)
				(type default)
			)
			(fill yes)
			(layer "F.SilkS")
		)
		(fp_rect
			(start -2.450084 2.999994)
			(end 2.450084 -2.999994)
			(stroke
				(width 0)
				(type default)
			)
			(fill no)
			(layer "F.CrtYd")
		)
		(fp_poly
			(pts
				(xy -2.8194 3.6322) (xy -2.8194 -3.6322) (xy 2.8194 -3.6322) (xy 2.8194 1.18364) (xy 2.450084 1.18364)
				(xy 2.450084 -2.999994) (xy -2.450084 -2.999994) (xy -2.450084 2.999994) (xy 2.450084 2.999994)
				(xy 2.450084 1.18618) (xy 2.8194 1.18618) (xy 2.8194 3.6322)
			)
			(stroke
				(width 0)
				(type default)
			)
			(fill no)
			(layer "F.CrtYd")
		)
		(fp_rect
			(start -2.8194 3.6322)
			(end 2.8194 -3.6322)
			(stroke
				(width 0)
				(type default)
			)
			(fill no)
			(layer "F.Fab")
		)
		(pad "1" smd rect
			(at -1.905 2.54 180)
			(size 0.635 1.651)
			(layers "F.Cu" "F.Mask" "F.Paste")
			(net "P5V_HDD35")
		)
		(pad "2" smd rect
			(at -0.635 2.54 180)
			(size 0.635 1.651)
			(layers "F.Cu" "F.Mask" "F.Paste")
			(net "P5V_HDD35")
		)
		(pad "3" smd rect
			(at 0.635 2.54 180)
			(size 0.635 1.651)
			(layers "F.Cu" "F.Mask" "F.Paste")
			(net "P5V_HDD35")
		)
		(pad "4" smd rect
			(at 1.905 2.54 180)
			(size 0.635 1.651)
			(layers "F.Cu" "F.Mask" "F.Paste")
			(net "SW_HDD_P35")
		)
		(pad "5" smd rect
			(at 1.905 -2.54 180)
			(size 0.635 1.651)
			(layers "F.Cu" "F.Mask" "F.Paste")
			(net "P5V_B_4")
		)
		(pad "6" smd rect
			(at 0.635 -2.54 180)
			(size 0.635 1.651)
			(layers "F.Cu" "F.Mask" "F.Paste")
			(net "P5V_B_4")
		)
		(pad "7" smd rect
			(at -0.635 -2.54 180)
			(size 0.635 1.651)
			(layers "F.Cu" "F.Mask" "F.Paste")
			(net "P5V_B_4")
		)
		(pad "8" smd rect
			(at -1.905 -2.54 180)
			(size 0.635 1.651)
			(layers "F.Cu" "F.Mask" "F.Paste")
			(net "P5V_B_4")
		)
	)
	(footprint ""
		(layer "F.Cu")
		(at 114.8334 -33.782 -90)
		(property "Reference" "C381"
			(at 0 0 270)
			(layer "F.SilkS")
			(hide yes)
			(effects
				(font
					(size 1.27 1.27)
				)
			)
		)
		(property "Value" "SC1U16V3KX-5GP"
			(at 0 -2.8194 270)
			(unlocked yes)
			(layer "F.Fab")
			(hide yes)
			(effects
				(font
					(size 1.016 1.016)
					(thickness 0.1524)
				)
			)
		)
		(property "Device Type" "C603H36"
			(at 0 -4.3434 270)
			(unlocked yes)
			(layer "F.Fab")
			(hide yes)
			(effects
				(font
					(size 1.016 1.016)
					(thickness 0.1524)
				)
			)
		)
		(duplicate_pad_numbers_are_jumpers no)
		(fp_line
			(start 0.508 0)
			(end -0.508 0)
			(stroke
				(width 0.2032)
				(type default)
			)
			(layer "F.SilkS")
		)
		(fp_rect
			(start -0.5842 1.3335)
			(end 0.5842 -1.3335)
			(stroke
				(width 0)
				(type default)
			)
			(fill no)
			(layer "F.CrtYd")
		)
		(fp_rect
			(start -0.5842 1.3335)
			(end 0.5842 -1.3335)
			(stroke
				(width 0)
				(type default)
			)
			(fill no)
			(layer "F.Fab")
		)
		(pad "1" smd custom
			(at 0 -0.762 270)
			(size 0.2159 0.2159)
			(layers "F.Cu" "F.Mask" "F.Paste")
			(net "P5V_HDD27")
			(options
				(clearance outline)
				(anchor circle)
			)
			(primitives
				(gr_poly
					(pts
						(arc
							(start -0.3302 -0.4318)
							(mid -0.402042 -0.402042)
							(end -0.4318 -0.3302)
						)
						(arc
							(start -0.4318 0.3302)
							(mid -0.402042 0.402042)
							(end -0.3302 0.4318)
						)
						(arc
							(start 0.3302 0.4318)
							(mid 0.402042 0.402042)
							(end 0.4318 0.3302)
						)
						(arc
							(start 0.4318 -0.3302)
							(mid 0.402042 -0.402042)
							(end 0.3302 -0.4318)
						)
					)
					(width 0)
					(fill yes)
				)
			)
		)
		(pad "2" smd custom
			(at 0 0.762 270)
			(size 0.2159 0.2159)
			(layers "F.Cu" "F.Mask" "F.Paste")
			(net "GND")
			(options
				(clearance outline)
				(anchor circle)
			)
			(primitives
				(gr_poly
					(pts
						(arc
							(start -0.3302 -0.4318)
							(mid -0.402042 -0.402042)
							(end -0.4318 -0.3302)
						)
						(arc
							(start -0.4318 0.3302)
							(mid -0.402042 0.402042)
							(end -0.3302 0.4318)
						)
						(arc
							(start 0.3302 0.4318)
							(mid 0.402042 0.402042)
							(end 0.4318 0.3302)
						)
						(arc
							(start 0.4318 -0.3302)
							(mid 0.402042 -0.402042)
							(end 0.3302 -0.4318)
						)
					)
					(width 0)
					(fill yes)
				)
			)
		)
	)
	(footprint ""
		(layer "F.Cu")
		(at 426.085 -147.066 -90)
		(property "Reference" "R552"
			(at 0 0 270)
			(layer "F.SilkS")
			(hide yes)
			(effects
				(font
					(size 1.27 1.27)
				)
			)
		)
		(property "Value" "2R6F-GP"
			(at -0.0508 -4.8514 270)
			(unlocked yes)
			(layer "F.Fab")
			(hide yes)
			(effects
				(font
					(size 1.016 1.016)
					(thickness 0.1524)
				)
			)
		)
		(property "Device Type" "R1206H26"
			(at 0 -6.3754 270)
			(unlocked yes)
			(layer "F.Fab")
			(hide yes)
			(effects
				(font
					(size 1.016 1.016)
					(thickness 0.1524)
				)
			)
		)
		(duplicate_pad_numbers_are_jumpers no)
		(fp_line
			(start -1.016 2.2352)
			(end -1.016 -2.2352)
			(stroke
				(width 0.1524)
				(type default)
			)
			(layer "F.SilkS")
		)
		(fp_line
			(start 1.016 2.2352)
			(end -1.016 2.2352)
			(stroke
				(width 0.1524)
				(type default)
			)
			(layer "F.SilkS")
		)
		(fp_line
			(start -1.016 -2.2352)
			(end 1.016 -2.2352)
			(stroke
				(width 0.1524)
				(type default)
			)
			(layer "F.SilkS")
		)
		(fp_line
			(start 1.016 -2.2352)
			(end 1.016 2.2352)
			(stroke
				(width 0.1524)
				(type default)
			)
			(layer "F.SilkS")
		)
		(fp_rect
			(start -1.0922 2.3114)
			(end 1.0922 -2.3114)
			(stroke
				(width 0)
				(type default)
			)
			(fill no)
			(layer "F.CrtYd")
		)
		(fp_poly
			(pts
				(xy -1.0922 -2.3114) (xy 1.0922 -2.3114) (xy 1.0922 2.3114) (xy -1.0922 2.3114)
			)
			(stroke
				(width 0)
				(type default)
			)
			(fill no)
			(layer "F.Fab")
		)
		(pad "1" smd rect
			(at 0 -1.397 270)
			(size 1.651 1.27)
			(layers "F.Cu" "F.Mask" "F.Paste")
			(net "P5V_HDD21")
		)
		(pad "2" smd rect
			(at 0 1.397 270)
			(size 1.651 1.27)
			(layers "F.Cu" "F.Mask" "F.Paste")
			(net "5V_PRE_21")
		)
	)
	(footprint ""
		(layer "F.Cu")
		(at 369.57 -135.509 90)
		(property "Reference" "R523"
			(at 0 0 90)
			(layer "F.SilkS")
			(hide yes)
			(effects
				(font
					(size 1.27 1.27)
				)
			)
		)
		(property "Value" "200KR2F-L-GP"
			(at 0.064008 -3.993896 90)
			(unlocked yes)
			(layer "F.Fab")
			(hide yes)
			(effects
				(font
					(size 1.016 1.016)
					(thickness 0.1524)
				)
			)
		)
		(property "Device Type" "R402H16"
			(at 0.064008 -5.517896 90)
			(unlocked yes)
			(layer "F.Fab")
			(hide yes)
			(effects
				(font
					(size 1.016 1.016)
					(thickness 0.1524)
				)
			)
		)
		(duplicate_pad_numbers_are_jumpers no)
		(fp_line
			(start 0.508 -0.9398)
			(end -0.508 -0.9398)
			(stroke
				(width 0.1524)
				(type default)
			)
			(layer "F.SilkS")
		)
		(fp_line
			(start -0.508 -0.9398)
			(end -0.508 0.9398)
			(stroke
				(width 0.1524)
				(type default)
			)
			(layer "F.SilkS")
		)
		(fp_rect
			(start -0.508 0.9398)
			(end 0.508 -0.9398)
			(stroke
				(width 0)
				(type default)
			)
			(fill no)
			(layer "F.CrtYd")
		)
		(fp_rect
			(start -0.508 0.9398)
			(end 0.508 -0.9398)
			(stroke
				(width 0)
				(type default)
			)
			(fill no)
			(layer "F.Fab")
		)
		(pad "1" smd custom
			(at 0 -0.4445 90)
			(size 0.1397 0.1397)
			(layers "F.Cu" "F.Mask" "F.Paste")
			(net "SW_HDD_R19")
			(options
				(clearance outline)
				(anchor circle)
			)
			(primitives
				(gr_poly
					(pts
						(arc
							(start -0.1778 -0.2794)
							(mid -0.249642 -0.249642)
							(end -0.2794 -0.1778)
						)
						(arc
							(start -0.2794 0.1778)
							(mid -0.249642 0.249642)
							(end -0.1778 0.2794)
						)
						(arc
							(start 0.1778 0.2794)
							(mid 0.249642 0.249642)
							(end 0.2794 0.1778)
						)
						(arc
							(start 0.2794 -0.1778)
							(mid 0.249642 -0.249642)
							(end 0.1778 -0.2794)
						)
					)
					(width 0)
					(fill yes)
				)
			)
		)
		(pad "2" smd custom
			(at 0 0.4445 90)
			(size 0.1397 0.1397)
			(layers "F.Cu" "F.Mask" "F.Paste")
			(net "SW_HDD_N19")
			(options
				(clearance outline)
				(anchor circle)
			)
			(primitives
				(gr_poly
					(pts
						(arc
							(start -0.1778 -0.2794)
							(mid -0.249642 -0.249642)
							(end -0.2794 -0.1778)
						)
						(arc
							(start -0.2794 0.1778)
							(mid -0.249642 0.249642)
							(end -0.1778 0.2794)
						)
						(arc
							(start 0.1778 0.2794)
							(mid 0.249642 0.249642)
							(end 0.2794 0.1778)
						)
						(arc
							(start 0.2794 -0.1778)
							(mid 0.249642 -0.249642)
							(end 0.1778 -0.2794)
						)
					)
					(width 0)
					(fill yes)
				)
			)
		)
	)
	(footprint ""
		(layer "F.Cu")
		(at 173.99 -361.696)
		(property "Reference" "C546"
			(at 0 0 0)
			(layer "F.SilkS")
			(hide yes)
			(effects
				(font
					(size 1.27 1.27)
				)
			)
		)
		(property "Value" "SCD1U25V2KX-2-GP"
			(at 1.1811 -2.7051 0)
			(unlocked yes)
			(layer "F.Fab")
			(hide yes)
			(effects
				(font
					(size 1.016 1.016)
					(thickness 0.1524)
				)
			)
		)
		(property "Device Type" "C402H22"
			(at 1.1811 -4.2291 0)
			(unlocked yes)
			(layer "F.Fab")
			(hide yes)
			(effects
				(font
					(size 1.016 1.016)
					(thickness 0.1524)
				)
			)
		)
		(duplicate_pad_numbers_are_jumpers no)
		(fp_rect
			(start -0.4318 0.9525)
			(end 0.4318 -0.9525)
			(stroke
				(width 0)
				(type default)
			)
			(fill no)
			(layer "F.CrtYd")
		)
		(fp_rect
			(start -0.4318 0.9525)
			(end 0.4318 -0.9525)
			(stroke
				(width 0)
				(type default)
			)
			(fill no)
			(layer "F.Fab")
		)
		(pad "1" smd custom
			(at 0 -0.4445)
			(size 0.1524 0.1524)
			(layers "F.Cu" "F.Mask" "F.Paste")
			(net "MB0_ISET_R")
			(options
				(clearance outline)
				(anchor circle)
			)
			(primitives
				(gr_poly
					(pts
						(arc
							(start 0.3048 -0.2032)
							(mid 0.275042 -0.275042)
							(end 0.2032 -0.3048)
						)
						(arc
							(start -0.2032 -0.3048)
							(mid -0.275042 -0.275042)
							(end -0.3048 -0.2032)
						)
						(arc
							(start -0.3048 0.2032)
							(mid -0.275042 0.275042)
							(end -0.2032 0.3048)
						)
						(arc
							(start 0.2032 0.3048)
							(mid 0.275042 0.275042)
							(end 0.3048 0.2032)
						)
					)
					(width 0)
					(fill yes)
				)
			)
		)
		(pad "2" smd custom
			(at 0 0.4445)
			(size 0.1524 0.1524)
			(layers "F.Cu" "F.Mask" "F.Paste")
			(net "AGND_CURRENT_MON")
			(options
				(clearance outline)
				(anchor circle)
			)
			(primitives
				(gr_poly
					(pts
						(arc
							(start 0.3048 -0.2032)
							(mid 0.275042 -0.275042)
							(end 0.2032 -0.3048)
						)
						(arc
							(start -0.2032 -0.3048)
							(mid -0.275042 -0.275042)
							(end -0.3048 -0.2032)
						)
						(arc
							(start -0.3048 0.2032)
							(mid -0.275042 0.275042)
							(end -0.2032 0.3048)
						)
						(arc
							(start 0.2032 0.3048)
							(mid 0.275042 0.275042)
							(end 0.3048 0.2032)
						)
					)
					(width 0)
					(fill yes)
				)
			)
		)
	)
	(footprint ""
		(layer "F.Cu")
		(at 288.064448 -347.541342 180)
		(property "Reference" "R1072"
			(at 0 0 180)
			(layer "F.SilkS")
			(hide yes)
			(effects
				(font
					(size 1.27 1.27)
				)
			)
		)
		(property "Value" "4K7R2F-GP"
			(at 0.064008 -3.993896 180)
			(unlocked yes)
			(layer "F.Fab")
			(hide yes)
			(effects
				(font
					(size 1.016 1.016)
					(thickness 0.1524)
				)
			)
		)
		(property "Device Type" "R402H16"
			(at 0.064008 -5.517896 180)
			(unlocked yes)
			(layer "F.Fab")
			(hide yes)
			(effects
				(font
					(size 1.016 1.016)
					(thickness 0.1524)
				)
			)
		)
		(duplicate_pad_numbers_are_jumpers no)
		(fp_line
			(start 0.508 -0.9398)
			(end -0.508 -0.9398)
			(stroke
				(width 0.1524)
				(type default)
			)
			(layer "F.SilkS")
		)
		(fp_line
			(start -0.508 -0.9398)
			(end -0.508 0.9398)
			(stroke
				(width 0.1524)
				(type default)
			)
			(layer "F.SilkS")
		)
		(fp_rect
			(start -0.508 0.9398)
			(end 0.508 -0.9398)
			(stroke
				(width 0)
				(type default)
			)
			(fill no)
			(layer "F.CrtYd")
		)
		(fp_rect
			(start -0.508 0.9398)
			(end 0.508 -0.9398)
			(stroke
				(width 0)
				(type default)
			)
			(fill no)
			(layer "F.Fab")
		)
		(pad "1" smd custom
			(at 0 -0.4445 180)
			(size 0.1397 0.1397)
			(layers "F.Cu" "F.Mask" "F.Paste")
			(net "P3V3_STBY_B")
			(options
				(clearance outline)
				(anchor circle)
			)
			(primitives
				(gr_poly
					(pts
						(arc
							(start -0.1778 -0.2794)
							(mid -0.249642 -0.249642)
							(end -0.2794 -0.1778)
						)
						(arc
							(start -0.2794 0.1778)
							(mid -0.249642 0.249642)
							(end -0.1778 0.2794)
						)
						(arc
							(start 0.1778 0.2794)
							(mid 0.249642 0.249642)
							(end 0.2794 0.1778)
						)
						(arc
							(start 0.2794 -0.1778)
							(mid 0.249642 -0.249642)
							(end 0.1778 -0.2794)
						)
					)
					(width 0)
					(fill yes)
				)
			)
		)
		(pad "2" smd custom
			(at 0 0.4445 180)
			(size 0.1397 0.1397)
			(layers "F.Cu" "F.Mask" "F.Paste")
			(net "MAX31790_B_ADD0")
			(options
				(clearance outline)
				(anchor circle)
			)
			(primitives
				(gr_poly
					(pts
						(arc
							(start -0.1778 -0.2794)
							(mid -0.249642 -0.249642)
							(end -0.2794 -0.1778)
						)
						(arc
							(start -0.2794 0.1778)
							(mid -0.249642 0.249642)
							(end -0.1778 0.2794)
						)
						(arc
							(start 0.1778 0.2794)
							(mid 0.249642 0.249642)
							(end 0.2794 0.1778)
						)
						(arc
							(start 0.2794 -0.1778)
							(mid 0.249642 -0.249642)
							(end 0.1778 -0.2794)
						)
					)
					(width 0)
					(fill yes)
				)
			)
		)
	)
	(footprint ""
		(layer "F.Cu")
		(at 265.075924 -367.448846 180)
		(property "Reference" "R1"
			(at 0 0 180)
			(layer "F.SilkS")
			(hide yes)
			(effects
				(font
					(size 1.27 1.27)
				)
			)
		)
		(property "Value" "10KR2F-2-GP"
			(at 0.064008 -3.993896 180)
			(unlocked yes)
			(layer "F.Fab")
			(hide yes)
			(effects
				(font
					(size 1.016 1.016)
					(thickness 0.1524)
				)
			)
		)
		(property "Device Type" "R402H16"
			(at 0.064008 -5.517896 180)
			(unlocked yes)
			(layer "F.Fab")
			(hide yes)
			(effects
				(font
					(size 1.016 1.016)
					(thickness 0.1524)
				)
			)
		)
		(duplicate_pad_numbers_are_jumpers no)
		(fp_line
			(start 0.508 -0.9398)
			(end -0.508 -0.9398)
			(stroke
				(width 0.1524)
				(type default)
			)
			(layer "F.SilkS")
		)
		(fp_line
			(start -0.508 -0.9398)
			(end -0.508 0.9398)
			(stroke
				(width 0.1524)
				(type default)
			)
			(layer "F.SilkS")
		)
		(fp_rect
			(start -0.508 0.9398)
			(end 0.508 -0.9398)
			(stroke
				(width 0)
				(type default)
			)
			(fill no)
			(layer "F.CrtYd")
		)
		(fp_rect
			(start -0.508 0.9398)
			(end 0.508 -0.9398)
			(stroke
				(width 0)
				(type default)
			)
			(fill no)
			(layer "F.Fab")
		)
		(pad "1" smd custom
			(at 0 -0.4445 180)
			(size 0.1397 0.1397)
			(layers "F.Cu" "F.Mask" "F.Paste")
			(net "P12V_IN")
			(options
				(clearance outline)
				(anchor circle)
			)
			(primitives
				(gr_poly
					(pts
						(arc
							(start -0.1778 -0.2794)
							(mid -0.249642 -0.249642)
							(end -0.2794 -0.1778)
						)
						(arc
							(start -0.2794 0.1778)
							(mid -0.249642 0.249642)
							(end -0.1778 0.2794)
						)
						(arc
							(start 0.1778 0.2794)
							(mid 0.249642 0.249642)
							(end 0.2794 0.1778)
						)
						(arc
							(start 0.2794 -0.1778)
							(mid 0.249642 -0.249642)
							(end 0.1778 -0.2794)
						)
					)
					(width 0)
					(fill yes)
				)
			)
		)
		(pad "2" smd custom
			(at 0 0.4445 180)
			(size 0.1397 0.1397)
			(layers "F.Cu" "F.Mask" "F.Paste")
			(net "DPB_PWR_BTN_BUF_B")
			(options
				(clearance outline)
				(anchor circle)
			)
			(primitives
				(gr_poly
					(pts
						(arc
							(start -0.1778 -0.2794)
							(mid -0.249642 -0.249642)
							(end -0.2794 -0.1778)
						)
						(arc
							(start -0.2794 0.1778)
							(mid -0.249642 0.249642)
							(end -0.1778 0.2794)
						)
						(arc
							(start 0.1778 0.2794)
							(mid 0.249642 0.249642)
							(end 0.2794 0.1778)
						)
						(arc
							(start 0.2794 -0.1778)
							(mid 0.249642 -0.249642)
							(end 0.1778 -0.2794)
						)
					)
					(width 0)
					(fill yes)
				)
			)
		)
	)
)
